(kicad_pcb
	(version 20260206)
	(generator "pcbnew")
	(generator_version "10.0")
	(general
		(thickness 1.6)
		(legacy_teardrops no)
	)
	(paper "A4")
	(title_block
		(title "12092022_DA0F0TFB6D0_F0T_FAN_BOARD_MP5048_D_brd_v02_OCP.brd")
		(comment 1 "Grand Teton / footprints 731-735 of 924")
	)
	(layers
		(0 "F.Cu" signal "TOP")
		(4 "In1.Cu" signal "GND")
		(6 "In2.Cu" signal "IN1")
		(8 "In3.Cu" signal "IN2")
		(10 "In4.Cu" signal "GND1")
		(2 "B.Cu" signal "BOTTOM")
		(9 "F.Adhes" user "F.Adhesive")
		(11 "B.Adhes" user "B.Adhesive")
		(13 "F.Paste" user "Package Geometry/Pastemask Top")
		(15 "B.Paste" user "Package Geometry/Pastemask Bottom")
		(5 "F.SilkS" user "Ref Des/Silkscreen Top")
		(7 "B.SilkS" user "Ref Des/Silkscreen Bottom")
		(1 "F.Mask" user "Board Geometry/Soldermask Top")
		(3 "B.Mask" user "Board Geometry/Soldermask Bottom")
		(17 "Dwgs.User" user "User.Drawings")
		(19 "Cmts.User" user "User.Comments")
		(21 "Eco1.User" user "User.Eco1")
		(23 "Eco2.User" user "User.Eco2")
		(25 "Edge.Cuts" user "Board Geometry/Outline")
		(27 "Margin" user)
		(31 "F.CrtYd" user "Package Geometry/Place Bound Top")
		(29 "B.CrtYd" user "Package Geometry/Place Bound Bottom")
		(35 "F.Fab" user "Ref Des/Assembly Top")
		(33 "B.Fab" user "Ref Des/Assembly Bottom")
	)
	(footprint ""
		(layer "B.Cu")
		(at 7.747 -249.428 -90)
		(property "Reference" "PC50"
			(at 0 0 90)
			(layer "B.SilkS")
			(hide yes)
			(effects
				(font
					(size 1.27 1.27)
				)
				(justify mirror)
			)
		)
		(property "Value" ""
			(at 0 0 90)
			(layer "B.Fab")
			(effects
				(font
					(size 1.27 1.27)
				)
				(justify mirror)
			)
		)
		(duplicate_pad_numbers_are_jumpers no)
		(fp_line
			(start -0.7874 0.4064)
			(end 0.7874 0.4064)
			(stroke
				(width 0.1524)
				(type default)
			)
			(layer "B.SilkS")
		)
		(fp_line
			(start 0.7874 0.4064)
			(end 0.7874 -0.4064)
			(stroke
				(width 0.1524)
				(type default)
			)
			(layer "B.SilkS")
		)
		(fp_line
			(start -0.7874 -0.4064)
			(end -0.7874 0.4064)
			(stroke
				(width 0.1524)
				(type default)
			)
			(layer "B.SilkS")
		)
		(fp_line
			(start 0.7874 -0.4064)
			(end -0.7874 -0.4064)
			(stroke
				(width 0.1524)
				(type default)
			)
			(layer "B.SilkS")
		)
		(fp_line
			(start -0.67945 0.3048)
			(end -0.120396 0.3048)
			(stroke
				(width 0.1)
				(type default)
			)
			(layer "B.Fab")
		)
		(fp_line
			(start -0.120396 0.3048)
			(end -0.120396 0.2794)
			(stroke
				(width 0.1)
				(type default)
			)
			(layer "B.Fab")
		)
		(fp_line
			(start 0.12065 0.3048)
			(end 0.67945 0.3048)
			(stroke
				(width 0.1)
				(type default)
			)
			(layer "B.Fab")
		)
		(fp_line
			(start 0.67945 0.3048)
			(end 0.67945 -0.305054)
			(stroke
				(width 0.1)
				(type default)
			)
			(layer "B.Fab")
		)
		(fp_line
			(start -0.120396 0.2794)
			(end 0.12065 0.2794)
			(stroke
				(width 0.1)
				(type default)
			)
			(layer "B.Fab")
		)
		(fp_line
			(start 0.12065 0.2794)
			(end 0.12065 0.3048)
			(stroke
				(width 0.1)
				(type default)
			)
			(layer "B.Fab")
		)
		(fp_line
			(start -0.12065 -0.2794)
			(end -0.12065 -0.3048)
			(stroke
				(width 0.1)
				(type default)
			)
			(layer "B.Fab")
		)
		(fp_line
			(start 0.12065 -0.2794)
			(end -0.12065 -0.2794)
			(stroke
				(width 0.1)
				(type default)
			)
			(layer "B.Fab")
		)
		(fp_line
			(start -0.67945 -0.3048)
			(end -0.67945 0.3048)
			(stroke
				(width 0.1)
				(type default)
			)
			(layer "B.Fab")
		)
		(fp_line
			(start -0.12065 -0.3048)
			(end -0.67945 -0.3048)
			(stroke
				(width 0.1)
				(type default)
			)
			(layer "B.Fab")
		)
		(fp_line
			(start 0.12065 -0.305054)
			(end 0.12065 -0.2794)
			(stroke
				(width 0.1)
				(type default)
			)
			(layer "B.Fab")
		)
		(fp_line
			(start 0.67945 -0.305054)
			(end 0.12065 -0.305054)
			(stroke
				(width 0.1)
				(type default)
			)
			(layer "B.Fab")
		)
		(pad "1" smd circle
			(at 0.40005 0 90)
			(size 0 0)
			(layers "B.Cu" "B.Mask" "B.Paste")
			(net "FAN_6_P3V_R")
		)
		(pad "2" smd circle
			(at -0.40005 0 90)
			(size 0 0)
			(layers "B.Cu" "B.Mask" "B.Paste")
			(net "GND")
		)
	)
	(footprint ""
		(layer "B.Cu")
		(at 44.069 -258.572 90)
		(property "Reference" "PC6"
			(at 0 0 90)
			(layer "B.SilkS")
			(hide yes)
			(effects
				(font
					(size 1.27 1.27)
				)
				(justify mirror)
			)
		)
		(property "Value" ""
			(at 0 0 90)
			(layer "B.Fab")
			(effects
				(font
					(size 1.27 1.27)
				)
				(justify mirror)
			)
		)
		(duplicate_pad_numbers_are_jumpers no)
		(fp_line
			(start 0.7874 -0.4064)
			(end -0.7874 -0.4064)
			(stroke
				(width 0.1524)
				(type default)
			)
			(layer "B.SilkS")
		)
		(fp_line
			(start -0.7874 -0.4064)
			(end -0.7874 0.4064)
			(stroke
				(width 0.1524)
				(type default)
			)
			(layer "B.SilkS")
		)
		(fp_line
			(start 0.7874 0.4064)
			(end 0.7874 -0.4064)
			(stroke
				(width 0.1524)
				(type default)
			)
			(layer "B.SilkS")
		)
		(fp_line
			(start -0.7874 0.4064)
			(end 0.7874 0.4064)
			(stroke
				(width 0.1524)
				(type default)
			)
			(layer "B.SilkS")
		)
		(fp_line
			(start 0.67945 -0.305054)
			(end 0.12065 -0.305054)
			(stroke
				(width 0.1)
				(type default)
			)
			(layer "B.Fab")
		)
		(fp_line
			(start 0.12065 -0.305054)
			(end 0.12065 -0.2794)
			(stroke
				(width 0.1)
				(type default)
			)
			(layer "B.Fab")
		)
		(fp_line
			(start -0.12065 -0.3048)
			(end -0.67945 -0.3048)
			(stroke
				(width 0.1)
				(type default)
			)
			(layer "B.Fab")
		)
		(fp_line
			(start -0.67945 -0.3048)
			(end -0.67945 0.3048)
			(stroke
				(width 0.1)
				(type default)
			)
			(layer "B.Fab")
		)
		(fp_line
			(start 0.12065 -0.2794)
			(end -0.12065 -0.2794)
			(stroke
				(width 0.1)
				(type default)
			)
			(layer "B.Fab")
		)
		(fp_line
			(start -0.12065 -0.2794)
			(end -0.12065 -0.3048)
			(stroke
				(width 0.1)
				(type default)
			)
			(layer "B.Fab")
		)
		(fp_line
			(start 0.12065 0.2794)
			(end 0.12065 0.3048)
			(stroke
				(width 0.1)
				(type default)
			)
			(layer "B.Fab")
		)
		(fp_line
			(start -0.120396 0.2794)
			(end 0.12065 0.2794)
			(stroke
				(width 0.1)
				(type default)
			)
			(layer "B.Fab")
		)
		(fp_line
			(start 0.67945 0.3048)
			(end 0.67945 -0.305054)
			(stroke
				(width 0.1)
				(type default)
			)
			(layer "B.Fab")
		)
		(fp_line
			(start 0.12065 0.3048)
			(end 0.67945 0.3048)
			(stroke
				(width 0.1)
				(type default)
			)
			(layer "B.Fab")
		)
		(fp_line
			(start -0.120396 0.3048)
			(end -0.120396 0.2794)
			(stroke
				(width 0.1)
				(type default)
			)
			(layer "B.Fab")
		)
		(fp_line
			(start -0.67945 0.3048)
			(end -0.120396 0.3048)
			(stroke
				(width 0.1)
				(type default)
			)
			(layer "B.Fab")
		)
		(pad "1" smd circle
			(at 0.40005 0 270)
			(size 0 0)
			(layers "B.Cu" "B.Mask" "B.Paste")
			(net "FAN_0_TIMER")
		)
		(pad "2" smd circle
			(at -0.40005 0 270)
			(size 0 0)
			(layers "B.Cu" "B.Mask" "B.Paste")
			(net "GND")
		)
	)
	(footprint ""
		(layer "B.Cu")
		(at 6.700012 -104.709976 180)
		(property "Reference" "J6"
			(at 2.001012 19.215354 0)
			(unlocked yes)
			(layer "B.SilkS")
			(effects
				(font
					(size 0.7874 0.5842)
					(thickness 0.1524)
				)
				(justify left mirror)
			)
		)
		(property "Value" ""
			(at 0 0 0)
			(layer "B.Fab")
			(effects
				(font
					(size 1.27 1.27)
				)
				(justify mirror)
			)
		)
		(duplicate_pad_numbers_are_jumpers no)
		(fp_line
			(start 4.350004 18.524982)
			(end -6.35 18.524982)
			(stroke
				(width 0.1524)
				(type default)
			)
			(layer "B.SilkS")
		)
		(fp_line
			(start 4.350004 -4.52501)
			(end 4.350004 18.524982)
			(stroke
				(width 0.1524)
				(type default)
			)
			(layer "B.SilkS")
		)
		(fp_line
			(start 1.249934 15.424912)
			(end -3.24993 15.424912)
			(stroke
				(width 0.1524)
				(type default)
			)
			(layer "B.SilkS")
		)
		(fp_line
			(start 1.249934 8.200136)
			(end 4.350004 8.200136)
			(stroke
				(width 0.1524)
				(type default)
			)
			(layer "B.SilkS")
		)
		(fp_line
			(start 1.249934 8.200136)
			(end 1.249934 15.424912)
			(stroke
				(width 0.1524)
				(type default)
			)
			(layer "B.SilkS")
		)
		(fp_line
			(start 1.249934 5.799836)
			(end 4.350004 5.799836)
			(stroke
				(width 0.1524)
				(type default)
			)
			(layer "B.SilkS")
		)
		(fp_line
			(start 1.249934 -1.42494)
			(end 1.249934 5.799836)
			(stroke
				(width 0.1524)
				(type default)
			)
			(layer "B.SilkS")
		)
		(fp_line
			(start -0.029972 -1.42494)
			(end 1.249934 -1.42494)
			(stroke
				(width 0.1524)
				(type default)
			)
			(layer "B.SilkS")
		)
		(fp_line
			(start -3.24993 15.424912)
			(end -3.24993 -1.42494)
			(stroke
				(width 0.1524)
				(type default)
			)
			(layer "B.SilkS")
		)
		(fp_line
			(start -3.24993 -1.42494)
			(end -1.96977 -1.42494)
			(stroke
				(width 0.1524)
				(type default)
			)
			(layer "B.SilkS")
		)
		(fp_line
			(start -6.35 18.524982)
			(end -6.35 -4.52501)
			(stroke
				(width 0.1524)
				(type default)
			)
			(layer "B.SilkS")
		)
		(fp_line
			(start -6.35 -4.52501)
			(end 4.350004 -4.52501)
			(stroke
				(width 0.1524)
				(type default)
			)
			(layer "B.SilkS")
		)
		(fp_poly
			(pts
				(xy 5.527802 -0.508) (xy 5.527802 0.508) (xy 4.511802 0)
			)
			(stroke
				(width 0)
				(type default)
			)
			(fill yes)
			(layer "B.SilkS")
		)
		(fp_line
			(start 4.350004 18.524982)
			(end -6.35 18.524982)
			(stroke
				(width 0.1)
				(type default)
			)
			(layer "B.Fab")
		)
		(fp_line
			(start 4.350004 -4.52501)
			(end 4.350004 18.524982)
			(stroke
				(width 0.1)
				(type default)
			)
			(layer "B.Fab")
		)
		(fp_line
			(start -6.35 18.524982)
			(end -6.35 -4.52501)
			(stroke
				(width 0.1)
				(type default)
			)
			(layer "B.Fab")
		)
		(fp_line
			(start -6.35 -4.52501)
			(end 4.350004 -4.52501)
			(stroke
				(width 0.1)
				(type default)
			)
			(layer "B.Fab")
		)
		(fp_poly
			(pts
				(xy 5.527802 -0.508) (xy 5.527802 0.508) (xy 4.511802 0)
			)
			(stroke
				(width 0)
				(type default)
			)
			(fill yes)
			(layer "B.Fab")
		)
		(pad "" np_thru_hole circle
			(at -0.999998 -1.89992 90)
			(size 1.4986 1.4986)
			(drill 1.4986)
			(layers "*.Cu" "*.Mask")
			(clearance 0.381)
			(thermal_gap 0.381)
		)
		(pad "1" thru_hole rect
			(at 0 0 90)
			(size 1.3716 1.3716)
			(drill 0.9652)
			(layers "*.Cu" "*.Mask")
			(remove_unused_layers no)
			(net "FAN_5_TACH_IL_D")
			(clearance 0.0508)
			(padstack
				(mode front_inner_back)
				(layer "Inner"
					(shape circle)
					(size 1.3716 1.3716)
					(clearance 0.0508)
				)
				(layer "B.Cu"
					(shape rect)
					(size 1.3716 1.3716)
					(thermal_gap 0.0508)
					(clearance 0.0508)
				)
			)
		)
		(pad "2" thru_hole circle
			(at -1.999996 0 90)
			(size 1.3716 1.3716)
			(drill 0.9652)
			(layers "*.Cu" "*.Mask")
			(remove_unused_layers no)
			(net "FAN_5_PWM_OL_R")
			(clearance 0.0508)
			(thermal_gap 0.0508)
		)
		(pad "3" thru_hole circle
			(at 0 1.999996 90)
			(size 1.3716 1.3716)
			(drill 0.9652)
			(layers "*.Cu" "*.Mask")
			(remove_unused_layers no)
			(net "FAN_5_PWM_IL_R")
			(clearance 0.0508)
			(thermal_gap 0.0508)
		)
		(pad "4" thru_hole circle
			(at -1.999996 1.999996 90)
			(size 1.3716 1.3716)
			(drill 0.9652)
			(layers "*.Cu" "*.Mask")
			(remove_unused_layers no)
			(net "FAN_5_PRESENT_R_N")
			(clearance 0.0508)
			(thermal_gap 0.0508)
		)
		(pad "5" thru_hole circle
			(at 0 3.999992 90)
			(size 1.3716 1.3716)
			(drill 0.9652)
			(layers "*.Cu" "*.Mask")
			(remove_unused_layers no)
			(net "P12V_LED_R1_FAN5")
			(clearance 0.0508)
			(thermal_gap 0.0508)
		)
		(pad "6" thru_hole circle
			(at -1.999996 3.999992 90)
			(size 1.3716 1.3716)
			(drill 0.9652)
			(layers "*.Cu" "*.Mask")
			(remove_unused_layers no)
			(net "SMB_FAN5_SCL_R")
			(clearance 0.0508)
			(thermal_gap 0.0508)
		)
		(pad "7" thru_hole circle
			(at 0 5.999988 90)
			(size 1.3716 1.3716)
			(drill 0.9652)
			(layers "*.Cu" "*.Mask")
			(remove_unused_layers no)
			(net "SMB_FAN5_SDA_R")
			(clearance 0.0508)
			(thermal_gap 0.0508)
		)
		(pad "8" thru_hole circle
			(at -1.999996 5.999988 90)
			(size 1.3716 1.3716)
			(drill 0.9652)
			(layers "*.Cu" "*.Mask")
			(remove_unused_layers no)
			(net "GND")
			(clearance 0.0508)
			(thermal_gap 0.0508)
		)
		(pad "9" thru_hole circle
			(at 0 7.999984 90)
			(size 1.3716 1.3716)
			(drill 0.9652)
			(layers "*.Cu" "*.Mask")
			(remove_unused_layers no)
			(net "GND")
			(clearance 0.0508)
			(thermal_gap 0.0508)
		)
		(pad "10" thru_hole circle
			(at -1.999996 7.999984 90)
			(size 1.3716 1.3716)
			(drill 0.9652)
			(layers "*.Cu" "*.Mask")
			(remove_unused_layers no)
			(net "P52V_FAN_5")
			(clearance 0.0508)
			(thermal_gap 0.0508)
		)
		(pad "11" thru_hole circle
			(at 0 9.99998 90)
			(size 1.3716 1.3716)
			(drill 0.9652)
			(layers "*.Cu" "*.Mask")
			(remove_unused_layers no)
			(net "P52V_FAN_5")
			(clearance 0.0508)
			(thermal_gap 0.0508)
		)
		(pad "12" thru_hole circle
			(at -1.999996 9.99998 90)
			(size 1.3716 1.3716)
			(drill 0.9652)
			(layers "*.Cu" "*.Mask")
			(remove_unused_layers no)
			(net "FAN_5_FAIL_R_LED_N")
			(clearance 0.0508)
			(thermal_gap 0.0508)
		)
		(pad "13" thru_hole circle
			(at 0 11.999976 90)
			(size 1.3716 1.3716)
			(drill 0.9652)
			(layers "*.Cu" "*.Mask")
			(remove_unused_layers no)
			(net "FAN_5_TACH_OL_D")
			(clearance 0.0508)
			(thermal_gap 0.0508)
		)
		(pad "14" thru_hole circle
			(at -1.999996 11.999976 90)
			(size 1.3716 1.3716)
			(drill 0.9652)
			(layers "*.Cu" "*.Mask")
			(remove_unused_layers no)
			(net "FAN_5_OK_R_LED_N")
			(clearance 0.0508)
			(thermal_gap 0.0508)
		)
		(pad "15" thru_hole circle
			(at 0 13.999972 90)
			(size 1.3716 1.3716)
			(drill 0.9652)
			(layers "*.Cu" "*.Mask")
			(remove_unused_layers no)
			(net "Net_603")
			(clearance 0.0508)
			(thermal_gap 0.0508)
		)
		(pad "16" thru_hole circle
			(at -1.999996 13.999972 90)
			(size 1.3716 1.3716)
			(drill 0.9652)
			(layers "*.Cu" "*.Mask")
			(remove_unused_layers no)
			(net "Net_602")
			(clearance 0.0508)
			(thermal_gap 0.0508)
		)
		(zone
			(layers "F.Cu" "B.Cu" "In1.Cu" "In2.Cu" "In3.Cu" "In4.Cu")
			(hatch none 0.5)
			(connect_pads
				(clearance 0)
			)
			(min_thickness 0.25)
			(keepout
				(tracks not_allowed)
				(vias allowed)
				(pads allowed)
				(copperpour not_allowed)
				(footprints allowed)
			)
			(placement
				(enabled no)
				(sheetname "")
			)
			(fill
				(thermal_gap 0.5)
				(thermal_bridge_width 0.5)
				(island_removal_mode 0)
			)
			(polygon
				(pts
					(arc
						(start 8.95731 -102.810056)
						(mid 6.44271 -102.810056)
						(end 8.95731 -102.810056)
					)
				)
			)
		)
	)
	(footprint ""
		(layer "B.Cu")
		(at 10.699242 -258.562856 90)
		(property "Reference" "PR76"
			(at 0 0 90)
			(layer "B.SilkS")
			(hide yes)
			(effects
				(font
					(size 1.27 1.27)
				)
				(justify mirror)
			)
		)
		(property "Value" ""
			(at 0 0 90)
			(layer "B.Fab")
			(effects
				(font
					(size 1.27 1.27)
				)
				(justify mirror)
			)
		)
		(duplicate_pad_numbers_are_jumpers no)
		(fp_line
			(start 0.7874 -0.4064)
			(end -0.7874 -0.4064)
			(stroke
				(width 0.1524)
				(type default)
			)
			(layer "B.SilkS")
		)
		(fp_line
			(start -0.7874 -0.4064)
			(end -0.7874 0.4064)
			(stroke
				(width 0.1524)
				(type default)
			)
			(layer "B.SilkS")
		)
		(fp_line
			(start 0.7874 0.4064)
			(end 0.7874 -0.4064)
			(stroke
				(width 0.1524)
				(type default)
			)
			(layer "B.SilkS")
		)
		(fp_line
			(start -0.7874 0.4064)
			(end 0.7874 0.4064)
			(stroke
				(width 0.1524)
				(type default)
			)
			(layer "B.SilkS")
		)
		(fp_line
			(start 0.67945 -0.305054)
			(end 0.12065 -0.305054)
			(stroke
				(width 0.1)
				(type default)
			)
			(layer "B.Fab")
		)
		(fp_line
			(start 0.12065 -0.305054)
			(end 0.12065 -0.2794)
			(stroke
				(width 0.1)
				(type default)
			)
			(layer "B.Fab")
		)
		(fp_line
			(start -0.12065 -0.3048)
			(end -0.67945 -0.3048)
			(stroke
				(width 0.1)
				(type default)
			)
			(layer "B.Fab")
		)
		(fp_line
			(start -0.67945 -0.3048)
			(end -0.67945 0.3048)
			(stroke
				(width 0.1)
				(type default)
			)
			(layer "B.Fab")
		)
		(fp_line
			(start 0.12065 -0.2794)
			(end -0.12065 -0.2794)
			(stroke
				(width 0.1)
				(type default)
			)
			(layer "B.Fab")
		)
		(fp_line
			(start -0.12065 -0.2794)
			(end -0.12065 -0.3048)
			(stroke
				(width 0.1)
				(type default)
			)
			(layer "B.Fab")
		)
		(fp_line
			(start 0.12065 0.2794)
			(end 0.12065 0.3048)
			(stroke
				(width 0.1)
				(type default)
			)
			(layer "B.Fab")
		)
		(fp_line
			(start -0.120396 0.2794)
			(end 0.12065 0.2794)
			(stroke
				(width 0.1)
				(type default)
			)
			(layer "B.Fab")
		)
		(fp_line
			(start 0.67945 0.3048)
			(end 0.67945 -0.305054)
			(stroke
				(width 0.1)
				(type default)
			)
			(layer "B.Fab")
		)
		(fp_line
			(start 0.12065 0.3048)
			(end 0.67945 0.3048)
			(stroke
				(width 0.1)
				(type default)
			)
			(layer "B.Fab")
		)
		(fp_line
			(start -0.120396 0.3048)
			(end -0.120396 0.2794)
			(stroke
				(width 0.1)
				(type default)
			)
			(layer "B.Fab")
		)
		(fp_line
			(start -0.67945 0.3048)
			(end -0.120396 0.3048)
			(stroke
				(width 0.1)
				(type default)
			)
			(layer "B.Fab")
		)
		(pad "1" smd circle
			(at 0.40005 0 270)
			(size 0 0)
			(layers "B.Cu" "B.Mask" "B.Paste")
			(net "FAN_7_TEMP")
		)
		(pad "2" smd circle
			(at -0.40005 0 270)
			(size 0 0)
			(layers "B.Cu" "B.Mask" "B.Paste")
			(net "GND")
		)
	)
	(footprint ""
		(layer "B.Cu")
		(at 16.2052 -90.989912 180)
		(property "Reference" "C2112"
			(at 0 0 0)
			(layer "B.SilkS")
			(hide yes)
			(effects
				(font
					(size 1.27 1.27)
				)
				(justify mirror)
			)
		)
		(property "Value" ""
			(at 0 0 0)
			(layer "B.Fab")
			(effects
				(font
					(size 1.27 1.27)
				)
				(justify mirror)
			)
		)
		(duplicate_pad_numbers_are_jumpers no)
		(fp_line
			(start 2.2098 0.9398)
			(end 2.2098 -0.9398)
			(stroke
				(width 0.1524)
				(type default)
			)
			(layer "B.SilkS")
		)
		(fp_line
			(start 2.2098 -0.9398)
			(end -2.2098 -0.9398)
			(stroke
				(width 0.1524)
				(type default)
			)
			(layer "B.SilkS")
		)
		(fp_line
			(start -2.2098 0.9398)
			(end 2.2098 0.9398)
			(stroke
				(width 0.1524)
				(type default)
			)
			(layer "B.SilkS")
		)
		(fp_line
			(start -2.2098 -0.9398)
			(end -2.2098 0.9398)
			(stroke
				(width 0.1524)
				(type default)
			)
			(layer "B.SilkS")
		)
		(fp_line
			(start 1.700022 0.899922)
			(end 1.700022 -0.899922)
			(stroke
				(width 0.1)
				(type default)
			)
			(layer "B.Fab")
		)
		(fp_line
			(start 1.700022 -0.899922)
			(end -1.700022 -0.899922)
			(stroke
				(width 0.1)
				(type default)
			)
			(layer "B.Fab")
		)
		(fp_line
			(start -1.700022 0.899922)
			(end 1.700022 0.899922)
			(stroke
				(width 0.1)
				(type default)
			)
			(layer "B.Fab")
		)
		(fp_line
			(start -1.700022 -0.899922)
			(end -1.700022 0.899922)
			(stroke
				(width 0.1)
				(type default)
			)
			(layer "B.Fab")
		)
		(pad "1" smd rect
			(at 1.4732 0 180)
			(size 1.1684 1.5748)
			(layers "B.Cu" "B.Mask" "B.Paste")
			(net "P52V_FAN_5")
		)
		(pad "2" smd rect
			(at -1.4732 0 180)
			(size 1.1684 1.5748)
			(layers "B.Cu" "B.Mask" "B.Paste")
			(net "GND")
		)
	)
)
